(kicad_pcb
	(version 20260206)
	(generator "pcbnew")
	(generator_version "10.0")
	(general
		(thickness 1.6)
		(legacy_teardrops no)
	)
	(paper "A4")
	(title_block
		(title "pdpb — Lightning_PDPB_BRD.brd")
		(comment 1 "Lightning (Wiwynn / Facebook NVMe JBOF) / footprints 801-808 of 1140")
	)
	(layers
		(0 "F.Cu" signal "TOP")
		(4 "In1.Cu" signal "L2GND")
		(6 "In2.Cu" signal "L3")
		(8 "In3.Cu" signal "L4VCC")
		(10 "In4.Cu" signal "L5VCC")
		(12 "In5.Cu" signal "L6")
		(14 "In6.Cu" signal "L7GND")
		(2 "B.Cu" signal "BOTTOM")
		(9 "F.Adhes" user "F.Adhesive")
		(11 "B.Adhes" user "B.Adhesive")
		(13 "F.Paste" user "Package Geometry/Pastemask Top")
		(15 "B.Paste" user "Package Geometry/Pastemask Bottom")
		(5 "F.SilkS" user "Ref Des/Silkscreen Top")
		(7 "B.SilkS" user "Ref Des/Silkscreen Bottom")
		(1 "F.Mask" user "Board Geometry/Soldermask Top")
		(3 "B.Mask" user "Board Geometry/Soldermask Bottom")
		(17 "Dwgs.User" user "User.Drawings")
		(19 "Cmts.User" user "User.Comments")
		(21 "Eco1.User" user "User.Eco1")
		(23 "Eco2.User" user "User.Eco2")
		(25 "Edge.Cuts" user "Board Geometry/Outline")
		(27 "Margin" user)
		(31 "F.CrtYd" user "Package Geometry/Place Bound Top")
		(29 "B.CrtYd" user "Package Geometry/Place Bound Bottom")
		(35 "F.Fab" user "Ref Des/Assembly Top")
		(33 "B.Fab" user "Ref Des/Assembly Bottom")
	)
	(footprint ""
		(layer "F.Cu")
		(at 29.845 -217.17 90)
		(property "Reference" "R414"
			(at 0 0 90)
			(layer "F.SilkS")
			(hide yes)
			(effects
				(font
					(size 1.27 1.27)
				)
			)
		)
		(property "Value" "0R2J-2-GP"
			(at 0.064008 -3.993896 90)
			(unlocked yes)
			(layer "F.Fab")
			(hide yes)
			(effects
				(font
					(size 1.016 1.016)
					(thickness 0.1524)
				)
			)
		)
		(property "Device Type" "R402H16"
			(at 0.064008 -5.517896 90)
			(unlocked yes)
			(layer "F.Fab")
			(hide yes)
			(effects
				(font
					(size 1.016 1.016)
					(thickness 0.1524)
				)
			)
		)
		(duplicate_pad_numbers_are_jumpers no)
		(fp_line
			(start 0.508 -0.9398)
			(end -0.508 -0.9398)
			(stroke
				(width 0.1524)
				(type default)
			)
			(layer "F.SilkS")
		)
		(fp_line
			(start -0.508 -0.9398)
			(end -0.508 0.9398)
			(stroke
				(width 0.1524)
				(type default)
			)
			(layer "F.SilkS")
		)
		(fp_rect
			(start -0.508 0.9398)
			(end 0.508 -0.9398)
			(stroke
				(width 0)
				(type default)
			)
			(fill no)
			(layer "F.CrtYd")
		)
		(fp_rect
			(start -0.508 0.9398)
			(end 0.508 -0.9398)
			(stroke
				(width 0)
				(type default)
			)
			(fill no)
			(layer "F.Fab")
		)
		(pad "1" smd custom
			(at 0 -0.4445 90)
			(size 0.1397 0.1397)
			(layers "F.Cu" "F.Mask" "F.Paste")
			(net "SDA_DR12_R")
			(options
				(clearance outline)
				(anchor circle)
			)
			(primitives
				(gr_poly
					(pts
						(arc
							(start -0.1778 -0.2794)
							(mid -0.249642 -0.249642)
							(end -0.2794 -0.1778)
						)
						(arc
							(start -0.2794 0.1778)
							(mid -0.249642 0.249642)
							(end -0.1778 0.2794)
						)
						(arc
							(start 0.1778 0.2794)
							(mid 0.249642 0.249642)
							(end 0.2794 0.1778)
						)
						(arc
							(start 0.2794 -0.1778)
							(mid 0.249642 -0.249642)
							(end 0.1778 -0.2794)
						)
					)
					(width 0)
					(fill yes)
				)
			)
		)
		(pad "2" smd custom
			(at 0 0.4445 90)
			(size 0.1397 0.1397)
			(layers "F.Cu" "F.Mask" "F.Paste")
			(net "SDA_DR12")
			(options
				(clearance outline)
				(anchor circle)
			)
			(primitives
				(gr_poly
					(pts
						(arc
							(start -0.1778 -0.2794)
							(mid -0.249642 -0.249642)
							(end -0.2794 -0.1778)
						)
						(arc
							(start -0.2794 0.1778)
							(mid -0.249642 0.249642)
							(end -0.1778 0.2794)
						)
						(arc
							(start 0.1778 0.2794)
							(mid 0.249642 0.249642)
							(end 0.2794 0.1778)
						)
						(arc
							(start 0.2794 -0.1778)
							(mid 0.249642 -0.249642)
							(end 0.1778 -0.2794)
						)
					)
					(width 0)
					(fill yes)
				)
			)
		)
	)
	(footprint ""
		(layer "F.Cu")
		(at 98.806 -317.246 -90)
		(property "Reference" "C9359"
			(at 0 0 270)
			(layer "F.SilkS")
			(hide yes)
			(effects
				(font
					(size 1.27 1.27)
				)
			)
		)
		(property "Value" "SC1KP50V2KX-1GP"
			(at 1.1811 -2.7051 270)
			(unlocked yes)
			(layer "F.Fab")
			(hide yes)
			(effects
				(font
					(size 1.016 1.016)
					(thickness 0.1524)
				)
			)
		)
		(property "Device Type" "C402H22"
			(at 1.1811 -4.2291 270)
			(unlocked yes)
			(layer "F.Fab")
			(hide yes)
			(effects
				(font
					(size 1.016 1.016)
					(thickness 0.1524)
				)
			)
		)
		(duplicate_pad_numbers_are_jumpers no)
		(fp_rect
			(start -0.4318 0.9525)
			(end 0.4318 -0.9525)
			(stroke
				(width 0)
				(type default)
			)
			(fill no)
			(layer "F.CrtYd")
		)
		(fp_rect
			(start -0.4318 0.9525)
			(end 0.4318 -0.9525)
			(stroke
				(width 0)
				(type default)
			)
			(fill no)
			(layer "F.Fab")
		)
		(pad "1" smd custom
			(at 0 -0.4445 270)
			(size 0.1524 0.1524)
			(layers "F.Cu" "F.Mask" "F.Paste")
			(net "SSD_PRSNT6")
			(options
				(clearance outline)
				(anchor circle)
			)
			(primitives
				(gr_poly
					(pts
						(arc
							(start 0.3048 -0.2032)
							(mid 0.275042 -0.275042)
							(end 0.2032 -0.3048)
						)
						(arc
							(start -0.2032 -0.3048)
							(mid -0.275042 -0.275042)
							(end -0.3048 -0.2032)
						)
						(arc
							(start -0.3048 0.2032)
							(mid -0.275042 0.275042)
							(end -0.2032 0.3048)
						)
						(arc
							(start 0.2032 0.3048)
							(mid 0.275042 0.275042)
							(end 0.3048 0.2032)
						)
					)
					(width 0)
					(fill yes)
				)
			)
		)
		(pad "2" smd custom
			(at 0 0.4445 270)
			(size 0.1524 0.1524)
			(layers "F.Cu" "F.Mask" "F.Paste")
			(net "GND")
			(options
				(clearance outline)
				(anchor circle)
			)
			(primitives
				(gr_poly
					(pts
						(arc
							(start 0.3048 -0.2032)
							(mid 0.275042 -0.275042)
							(end 0.2032 -0.3048)
						)
						(arc
							(start -0.2032 -0.3048)
							(mid -0.275042 -0.275042)
							(end -0.3048 -0.2032)
						)
						(arc
							(start -0.3048 0.2032)
							(mid -0.275042 0.275042)
							(end -0.2032 0.3048)
						)
						(arc
							(start 0.2032 0.3048)
							(mid 0.275042 0.275042)
							(end 0.3048 0.2032)
						)
					)
					(width 0)
					(fill yes)
				)
			)
		)
	)
	(footprint ""
		(layer "F.Cu")
		(at 247.904 -415.544)
		(property "Reference" "TP1"
			(at 0 0 0)
			(layer "F.SilkS")
			(hide yes)
			(effects
				(font
					(size 1.27 1.27)
				)
			)
		)
		(property "Value" "TPAD28-2-GP"
			(at -0.0127 -1.6637 0)
			(unlocked yes)
			(layer "F.Fab")
			(hide yes)
			(effects
				(font
					(size 1.016 1.016)
					(thickness 0.1524)
				)
			)
		)
		(property "Device Type" "TPAD28"
			(at -0.0127 -3.1877 0)
			(unlocked yes)
			(layer "F.Fab")
			(hide yes)
			(effects
				(font
					(size 1.016 1.016)
					(thickness 0.1524)
				)
			)
		)
		(duplicate_pad_numbers_are_jumpers no)
		(fp_poly
			(pts
				(arc
					(start 0.3556 0)
					(mid -0.3556 0)
					(end 0.3556 0)
				)
			)
			(stroke
				(width 0)
				(type default)
			)
			(fill no)
			(layer "F.CrtYd")
		)
		(fp_poly
			(pts
				(arc
					(start 0.6096 0)
					(mid -0.6096 0)
					(end 0.6096 0)
				)
			)
			(stroke
				(width 0)
				(type default)
			)
			(fill no)
			(layer "F.Fab")
		)
		(pad "1" smd circle
			(at 0 0)
			(size 0.7112 0.7112)
			(layers "F.Cu" "F.Mask" "F.Paste")
			(net "N70929042")
		)
	)
	(footprint ""
		(layer "F.Cu")
		(at 17.145 -492.887 -90)
		(property "Reference" "R143"
			(at 0 0 270)
			(layer "F.SilkS")
			(hide yes)
			(effects
				(font
					(size 1.27 1.27)
				)
			)
		)
		(property "Value" "4K7R2J-2-GP"
			(at 0.064008 -3.993896 270)
			(unlocked yes)
			(layer "F.Fab")
			(hide yes)
			(effects
				(font
					(size 1.016 1.016)
					(thickness 0.1524)
				)
			)
		)
		(property "Device Type" "R402H16"
			(at 0.064008 -5.517896 270)
			(unlocked yes)
			(layer "F.Fab")
			(hide yes)
			(effects
				(font
					(size 1.016 1.016)
					(thickness 0.1524)
				)
			)
		)
		(duplicate_pad_numbers_are_jumpers no)
		(fp_line
			(start -0.508 -0.9398)
			(end -0.508 0.9398)
			(stroke
				(width 0.1524)
				(type default)
			)
			(layer "F.SilkS")
		)
		(fp_line
			(start 0.508 -0.9398)
			(end -0.508 -0.9398)
			(stroke
				(width 0.1524)
				(type default)
			)
			(layer "F.SilkS")
		)
		(fp_rect
			(start -0.508 0.9398)
			(end 0.508 -0.9398)
			(stroke
				(width 0)
				(type default)
			)
			(fill no)
			(layer "F.CrtYd")
		)
		(fp_rect
			(start -0.508 0.9398)
			(end 0.508 -0.9398)
			(stroke
				(width 0)
				(type default)
			)
			(fill no)
			(layer "F.Fab")
		)
		(pad "1" smd custom
			(at 0 -0.4445 270)
			(size 0.1397 0.1397)
			(layers "F.Cu" "F.Mask" "F.Paste")
			(net "P12V")
			(options
				(clearance outline)
				(anchor circle)
			)
			(primitives
				(gr_poly
					(pts
						(arc
							(start -0.1778 -0.2794)
							(mid -0.249642 -0.249642)
							(end -0.2794 -0.1778)
						)
						(arc
							(start -0.2794 0.1778)
							(mid -0.249642 0.249642)
							(end -0.1778 0.2794)
						)
						(arc
							(start 0.1778 0.2794)
							(mid 0.249642 0.249642)
							(end 0.2794 0.1778)
						)
						(arc
							(start 0.2794 -0.1778)
							(mid 0.249642 -0.249642)
							(end 0.1778 -0.2794)
						)
					)
					(width 0)
					(fill yes)
				)
			)
		)
		(pad "2" smd custom
			(at 0 0.4445 270)
			(size 0.1397 0.1397)
			(layers "F.Cu" "F.Mask" "F.Paste")
			(net "SW_SSD5_R")
			(options
				(clearance outline)
				(anchor circle)
			)
			(primitives
				(gr_poly
					(pts
						(arc
							(start -0.1778 -0.2794)
							(mid -0.249642 -0.249642)
							(end -0.2794 -0.1778)
						)
						(arc
							(start -0.2794 0.1778)
							(mid -0.249642 0.249642)
							(end -0.1778 0.2794)
						)
						(arc
							(start 0.1778 0.2794)
							(mid 0.249642 0.249642)
							(end 0.2794 0.1778)
						)
						(arc
							(start 0.2794 -0.1778)
							(mid 0.249642 -0.249642)
							(end 0.1778 -0.2794)
						)
					)
					(width 0)
					(fill yes)
				)
			)
		)
	)
	(footprint ""
		(layer "F.Cu")
		(at 228.283516 -140.83411 180)
		(property "Reference" "SR1128"
			(at 0 0 180)
			(layer "F.SilkS")
			(hide yes)
			(effects
				(font
					(size 1.27 1.27)
				)
			)
		)
		(property "Value" "4K7R2J-2-GP"
			(at 0.064008 -3.993896 180)
			(unlocked yes)
			(layer "F.Fab")
			(hide yes)
			(effects
				(font
					(size 1.016 1.016)
					(thickness 0.1524)
				)
			)
		)
		(property "Device Type" "R402H16"
			(at 0.064008 -5.517896 180)
			(unlocked yes)
			(layer "F.Fab")
			(hide yes)
			(effects
				(font
					(size 1.016 1.016)
					(thickness 0.1524)
				)
			)
		)
		(duplicate_pad_numbers_are_jumpers no)
		(fp_line
			(start 0.508 -0.9398)
			(end -0.508 -0.9398)
			(stroke
				(width 0.1524)
				(type default)
			)
			(layer "F.SilkS")
		)
		(fp_line
			(start -0.508 -0.9398)
			(end -0.508 0.9398)
			(stroke
				(width 0.1524)
				(type default)
			)
			(layer "F.SilkS")
		)
		(fp_rect
			(start -0.508 0.9398)
			(end 0.508 -0.9398)
			(stroke
				(width 0)
				(type default)
			)
			(fill no)
			(layer "F.CrtYd")
		)
		(fp_rect
			(start -0.508 0.9398)
			(end 0.508 -0.9398)
			(stroke
				(width 0)
				(type default)
			)
			(fill no)
			(layer "F.Fab")
		)
		(pad "1" smd custom
			(at 0 -0.4445 180)
			(size 0.1397 0.1397)
			(layers "F.Cu" "F.Mask" "F.Paste")
			(net "P3V3")
			(options
				(clearance outline)
				(anchor circle)
			)
			(primitives
				(gr_poly
					(pts
						(arc
							(start -0.1778 -0.2794)
							(mid -0.249642 -0.249642)
							(end -0.2794 -0.1778)
						)
						(arc
							(start -0.2794 0.1778)
							(mid -0.249642 0.249642)
							(end -0.1778 0.2794)
						)
						(arc
							(start 0.1778 0.2794)
							(mid 0.249642 0.249642)
							(end 0.2794 0.1778)
						)
						(arc
							(start 0.2794 -0.1778)
							(mid 0.249642 -0.249642)
							(end 0.1778 -0.2794)
						)
					)
					(width 0)
					(fill yes)
				)
			)
		)
		(pad "2" smd custom
			(at 0 0.4445 180)
			(size 0.1397 0.1397)
			(layers "F.Cu" "F.Mask" "F.Paste")
			(net "SSD_ACT_DR3")
			(options
				(clearance outline)
				(anchor circle)
			)
			(primitives
				(gr_poly
					(pts
						(arc
							(start -0.1778 -0.2794)
							(mid -0.249642 -0.249642)
							(end -0.2794 -0.1778)
						)
						(arc
							(start -0.2794 0.1778)
							(mid -0.249642 0.249642)
							(end -0.1778 0.2794)
						)
						(arc
							(start 0.1778 0.2794)
							(mid 0.249642 0.249642)
							(end 0.2794 0.1778)
						)
						(arc
							(start 0.2794 -0.1778)
							(mid 0.249642 -0.249642)
							(end 0.1778 -0.2794)
						)
					)
					(width 0)
					(fill yes)
				)
			)
		)
	)
	(footprint ""
		(layer "F.Cu")
		(at 20.066 -64.38011 -90)
		(property "Reference" "R9873"
			(at 0 0 270)
			(layer "F.SilkS")
			(hide yes)
			(effects
				(font
					(size 1.27 1.27)
				)
			)
		)
		(property "Value" "0R2J-2-GP"
			(at 0.064008 -3.993896 270)
			(unlocked yes)
			(layer "F.Fab")
			(hide yes)
			(effects
				(font
					(size 1.016 1.016)
					(thickness 0.1524)
				)
			)
		)
		(property "Device Type" "R402H16"
			(at 0.064008 -5.517896 270)
			(unlocked yes)
			(layer "F.Fab")
			(hide yes)
			(effects
				(font
					(size 1.016 1.016)
					(thickness 0.1524)
				)
			)
		)
		(duplicate_pad_numbers_are_jumpers no)
		(fp_line
			(start -0.508 -0.9398)
			(end -0.508 0.9398)
			(stroke
				(width 0.1524)
				(type default)
			)
			(layer "F.SilkS")
		)
		(fp_line
			(start 0.508 -0.9398)
			(end -0.508 -0.9398)
			(stroke
				(width 0.1524)
				(type default)
			)
			(layer "F.SilkS")
		)
		(fp_rect
			(start -0.508 0.9398)
			(end 0.508 -0.9398)
			(stroke
				(width 0)
				(type default)
			)
			(fill no)
			(layer "F.CrtYd")
		)
		(fp_rect
			(start -0.508 0.9398)
			(end 0.508 -0.9398)
			(stroke
				(width 0)
				(type default)
			)
			(fill no)
			(layer "F.Fab")
		)
		(pad "1" smd custom
			(at 0 -0.4445 270)
			(size 0.1397 0.1397)
			(layers "F.Cu" "F.Mask" "F.Paste")
			(net "ATTN_LED_DR14_AND")
			(options
				(clearance outline)
				(anchor circle)
			)
			(primitives
				(gr_poly
					(pts
						(arc
							(start -0.1778 -0.2794)
							(mid -0.249642 -0.249642)
							(end -0.2794 -0.1778)
						)
						(arc
							(start -0.2794 0.1778)
							(mid -0.249642 0.249642)
							(end -0.1778 0.2794)
						)
						(arc
							(start 0.1778 0.2794)
							(mid 0.249642 0.249642)
							(end 0.2794 0.1778)
						)
						(arc
							(start 0.2794 -0.1778)
							(mid 0.249642 -0.249642)
							(end 0.1778 -0.2794)
						)
					)
					(width 0)
					(fill yes)
				)
			)
		)
		(pad "2" smd custom
			(at 0 0.4445 270)
			(size 0.1397 0.1397)
			(layers "F.Cu" "F.Mask" "F.Paste")
			(net "ATTN_LED_DR14_AND_R")
			(options
				(clearance outline)
				(anchor circle)
			)
			(primitives
				(gr_poly
					(pts
						(arc
							(start -0.1778 -0.2794)
							(mid -0.249642 -0.249642)
							(end -0.2794 -0.1778)
						)
						(arc
							(start -0.2794 0.1778)
							(mid -0.249642 0.249642)
							(end -0.1778 0.2794)
						)
						(arc
							(start 0.1778 0.2794)
							(mid 0.249642 0.249642)
							(end 0.2794 0.1778)
						)
						(arc
							(start 0.2794 -0.1778)
							(mid 0.249642 -0.249642)
							(end 0.1778 -0.2794)
						)
					)
					(width 0)
					(fill yes)
				)
			)
		)
	)
	(footprint ""
		(layer "F.Cu")
		(at 49.149 -144.526 -90)
		(property "Reference" "R9429"
			(at 0 0 270)
			(layer "F.SilkS")
			(hide yes)
			(effects
				(font
					(size 1.27 1.27)
				)
			)
		)
		(property "Value" "100R2J-2-GP"
			(at 0.064008 -3.993896 270)
			(unlocked yes)
			(layer "F.Fab")
			(hide yes)
			(effects
				(font
					(size 1.016 1.016)
					(thickness 0.1524)
				)
			)
		)
		(property "Device Type" "R402H14"
			(at 0.064008 -5.517896 270)
			(unlocked yes)
			(layer "F.Fab")
			(hide yes)
			(effects
				(font
					(size 1.016 1.016)
					(thickness 0.1524)
				)
			)
		)
		(duplicate_pad_numbers_are_jumpers no)
		(fp_line
			(start -0.508 -0.9398)
			(end -0.508 0.9398)
			(stroke
				(width 0.1524)
				(type default)
			)
			(layer "F.SilkS")
		)
		(fp_line
			(start 0.508 -0.9398)
			(end -0.508 -0.9398)
			(stroke
				(width 0.1524)
				(type default)
			)
			(layer "F.SilkS")
		)
		(fp_rect
			(start -0.508 0.9398)
			(end 0.508 -0.9398)
			(stroke
				(width 0)
				(type default)
			)
			(fill no)
			(layer "F.CrtYd")
		)
		(fp_rect
			(start -0.508 0.9398)
			(end 0.508 -0.9398)
			(stroke
				(width 0)
				(type default)
			)
			(fill no)
			(layer "F.Fab")
		)
		(pad "1" smd custom
			(at 0 -0.4445 270)
			(size 0.1397 0.1397)
			(layers "F.Cu" "F.Mask" "F.Paste")
			(net "P3V3")
			(options
				(clearance outline)
				(anchor circle)
			)
			(primitives
				(gr_poly
					(pts
						(arc
							(start -0.1778 -0.2794)
							(mid -0.249642 -0.249642)
							(end -0.2794 -0.1778)
						)
						(arc
							(start -0.2794 0.1778)
							(mid -0.249642 0.249642)
							(end -0.1778 0.2794)
						)
						(arc
							(start 0.1778 0.2794)
							(mid 0.249642 0.249642)
							(end 0.2794 0.1778)
						)
						(arc
							(start 0.2794 -0.1778)
							(mid 0.249642 -0.249642)
							(end 0.1778 -0.2794)
						)
					)
					(width 0)
					(fill yes)
				)
			)
		)
		(pad "2" smd custom
			(at 0 0.4445 270)
			(size 0.1397 0.1397)
			(layers "F.Cu" "F.Mask" "F.Paste")
			(net "DRV_ACT_8")
			(options
				(clearance outline)
				(anchor circle)
			)
			(primitives
				(gr_poly
					(pts
						(arc
							(start -0.1778 -0.2794)
							(mid -0.249642 -0.249642)
							(end -0.2794 -0.1778)
						)
						(arc
							(start -0.2794 0.1778)
							(mid -0.249642 0.249642)
							(end -0.1778 0.2794)
						)
						(arc
							(start 0.1778 0.2794)
							(mid 0.249642 0.249642)
							(end 0.2794 0.1778)
						)
						(arc
							(start 0.2794 -0.1778)
							(mid 0.249642 -0.249642)
							(end 0.1778 -0.2794)
						)
					)
					(width 0)
					(fill yes)
				)
			)
		)
	)
	(footprint ""
		(layer "F.Cu")
		(at 210.439 -44.704)
		(property "Reference" "R337"
			(at 0 0 0)
			(layer "F.SilkS")
			(hide yes)
			(effects
				(font
					(size 1.27 1.27)
				)
			)
		)
		(property "Value" "4K7R2F-GP"
			(at 0.064008 -3.993896 0)
			(unlocked yes)
			(layer "F.Fab")
			(hide yes)
			(effects
				(font
					(size 1.016 1.016)
					(thickness 0.1524)
				)
			)
		)
		(property "Device Type" "R402H16"
			(at 0.064008 -5.517896 0)
			(unlocked yes)
			(layer "F.Fab")
			(hide yes)
			(effects
				(font
					(size 1.016 1.016)
					(thickness 0.1524)
				)
			)
		)
		(duplicate_pad_numbers_are_jumpers no)
		(fp_line
			(start -0.508 -0.9398)
			(end -0.508 0.9398)
			(stroke
				(width 0.1524)
				(type default)
			)
			(layer "F.SilkS")
		)
		(fp_line
			(start 0.508 -0.9398)
			(end -0.508 -0.9398)
			(stroke
				(width 0.1524)
				(type default)
			)
			(layer "F.SilkS")
		)
		(fp_rect
			(start -0.508 0.9398)
			(end 0.508 -0.9398)
			(stroke
				(width 0)
				(type default)
			)
			(fill no)
			(layer "F.CrtYd")
		)
		(fp_rect
			(start -0.508 0.9398)
			(end 0.508 -0.9398)
			(stroke
				(width 0)
				(type default)
			)
			(fill no)
			(layer "F.Fab")
		)
		(pad "1" smd custom
			(at 0 -0.4445)
			(size 0.1397 0.1397)
			(layers "F.Cu" "F.Mask" "F.Paste")
			(net "I2C_B_TMP3_A1")
			(options
				(clearance outline)
				(anchor circle)
			)
			(primitives
				(gr_poly
					(pts
						(arc
							(start -0.1778 -0.2794)
							(mid -0.249642 -0.249642)
							(end -0.2794 -0.1778)
						)
						(arc
							(start -0.2794 0.1778)
							(mid -0.249642 0.249642)
							(end -0.1778 0.2794)
						)
						(arc
							(start 0.1778 0.2794)
							(mid 0.249642 0.249642)
							(end 0.2794 0.1778)
						)
						(arc
							(start 0.2794 -0.1778)
							(mid 0.249642 -0.249642)
							(end 0.1778 -0.2794)
						)
					)
					(width 0)
					(fill yes)
				)
			)
		)
		(pad "2" smd custom
			(at 0 0.4445)
			(size 0.1397 0.1397)
			(layers "F.Cu" "F.Mask" "F.Paste")
			(net "GND")
			(options
				(clearance outline)
				(anchor circle)
			)
			(primitives
				(gr_poly
					(pts
						(arc
							(start -0.1778 -0.2794)
							(mid -0.249642 -0.249642)
							(end -0.2794 -0.1778)
						)
						(arc
							(start -0.2794 0.1778)
							(mid -0.249642 0.249642)
							(end -0.1778 0.2794)
						)
						(arc
							(start 0.1778 0.2794)
							(mid 0.249642 0.249642)
							(end 0.2794 0.1778)
						)
						(arc
							(start 0.2794 -0.1778)
							(mid 0.249642 -0.249642)
							(end 0.1778 -0.2794)
						)
					)
					(width 0)
					(fill yes)
				)
			)
		)
	)
)
